#ISCELL
  pure_quanta quanta_title_block_c *
  *
#ISCELL
  standard offpage *
  page123_i1
#CELL
  pure_quanta q_res *
  page123_i10
#CELL
  pure_quanta bc847bpn *
  page123_i11
#CELL
  pure_quanta bc847bpn *
  page123_i12
#ISCELL
  logical_power universal_power *
  page123_i13
#CELL
  pure_quanta q_res *
  page123_i14
#CELL
  pure_quanta q_res *
  page123_i15
#CELL
  pure_quanta bc847bpn *
  page123_i16
#ISCELL
  logical_power universal_gnd *
  page123_i17
#CELL
  pure_quanta bc847bpn *
  page123_i18
#CELL
  pure_quanta q_res *
  page123_i19
#ISCELL
  standard offpage *
  page123_i2
#ISCELL
  logical_power universal_power *
  page123_i20
#ISCELL
  logical_power universal_power *
  page123_i21
#ISCELL
  logical_power universal_gnd *
  page123_i22
#CELL
  pure_quanta q_res *
  page123_i23
#ISCELL
  logical_power universal_power *
  page123_i24
#ISCELL
  standard offpage *
  page123_i25
#ISCELL
  standard offpage *
  page123_i26
#CELL
  pure_quanta q_res *
  page123_i27
#ISCELL
  logical_power universal_power *
  page123_i28
#CELL
  pure_quanta q_res *
  page123_i29
#ISCELL
  standard offpage *
  page123_i3
#ISCELL
  logical_power universal_power *
  page123_i30
#CELL
  pure_quanta q_res *
  page123_i31
#CELL
  pure_quanta q_res *
  page123_i32
#CELL
  pure_quanta q_res *
  page123_i33
#ISCELL
  standard offpage *
  page123_i34
#ISCELL
  standard offpage *
  page123_i35
#ISCELL
  logical_power universal_power *
  page123_i36
#CELL
  pure_quanta q_res *
  page123_i4
#CELL
  pure_quanta q_res *
  page123_i5
#CELL
  pure_quanta q_res *
  page123_i6
#CELL
  pure_quanta q_res *
  page123_i7
#CELL
  pure_quanta q_res *
  page123_i8
#ISCELL
  logical_power universal_power *
  page123_i9
